(kicad_pcb
	(version 20240108)
	(generator "pcbnew")
	(generator_version "8.0")
	(general
		(thickness 1.62)
		(legacy_teardrops no)
	)
	(paper "A4")
	(title_block
		(title "Jetson Orin Baseboard")
		(date "2025-03-12")
		(rev "1.3.4")
		(company "Antmicro Ltd")
		(comment 1 "www.antmicro.com")
		(comment 9 "footprints 249-251 of 677")
	)
	(layers
		(0 "F.Cu" signal)
		(1 "In1.Cu" signal)
		(2 "In2.Cu" signal)
		(3 "In3.Cu" signal)
		(4 "In4.Cu" jumper)
		(5 "In5.Cu" signal)
		(6 "In6.Cu" signal)
		(31 "B.Cu" signal)
		(32 "B.Adhes" user "B.Adhesive")
		(33 "F.Adhes" user "F.Adhesive")
		(34 "B.Paste" user)
		(35 "F.Paste" user)
		(36 "B.SilkS" user "B.Silkscreen")
		(37 "F.SilkS" user "F.Silkscreen")
		(38 "B.Mask" user)
		(39 "F.Mask" user)
		(40 "Dwgs.User" user "User.Drawings")
		(41 "Cmts.User" user "User.Comments")
		(42 "Eco1.User" user "User.Eco1")
		(43 "Eco2.User" user "User.Eco2")
		(44 "Edge.Cuts" user)
		(45 "Margin" user)
		(46 "B.CrtYd" user "B.Courtyard")
		(47 "F.CrtYd" user "F.Courtyard")
		(48 "B.Fab" user)
		(49 "F.Fab" user)
	)
	(footprint "antmicro-footprints:XDFN-2_1x0.60mm"
		(layer "F.Cu")
		(at 67.6 125.95 90)
		(property "Reference" "D60"
			(at 0.598 0.4 -90)
			(layer "F.SilkS")
			(effects
				(font
					(size 0.7 0.7)
					(thickness 0.15)
				)
				(justify left bottom)
			)
		)
		(property "Value" "TPD1E0B04_XDFN-2"
			(at 0 1.5 90)
			(layer "F.Fab")
			(effects
				(font
					(size 0.7 0.7)
					(thickness 0.15)
				)
				(justify left bottom)
			)
		)
		(property "Footprint" "antmicro-footprints:XDFN-2_1x0.60mm"
			(at 0 0 90)
			(layer "F.Fab")
			(hide yes)
			(effects
				(font
					(size 1.27 1.27)
					(thickness 0.15)
				)
			)
		)
		(property "Datasheet" "https://www.ti.com/general/docs/suppproductinfo.tsp?distId=26&gotoUrl=https://www.ti.com/lit/gpn/tpd1e0b04"
			(at 0 0 90)
			(layer "F.Fab")
			(hide yes)
			(effects
				(font
					(size 1.27 1.27)
					(thickness 0.15)
				)
			)
		)
		(property "MPN" "TPD1E0B04DPYR"
			(at 193.55 58.35 0)
			(layer "F.Fab")
			(hide yes)
			(effects
				(font
					(size 1 1)
					(thickness 0.15)
				)
			)
		)
		(property "Manufacturer" "Texas Instruments"
			(at 193.55 58.35 0)
			(layer "F.Fab")
			(hide yes)
			(effects
				(font
					(size 1 1)
					(thickness 0.15)
				)
			)
		)
		(property "Author" "Antmicro"
			(at 193.55 58.35 0)
			(layer "F.Fab")
			(hide yes)
			(effects
				(font
					(size 1 1)
					(thickness 0.15)
				)
			)
		)
		(property "License" "Apache-2.0"
			(at 193.55 58.35 0)
			(layer "F.Fab")
			(hide yes)
			(effects
				(font
					(size 1 1)
					(thickness 0.15)
				)
			)
		)
		(sheetname "Supply")
		(sheetfile "supply.kicad_sch")
		(attr smd)
		(fp_rect
			(start -0.725 -0.475)
			(end 0.725 0.475)
			(stroke
				(width 0.05)
				(type solid)
			)
			(fill none)
			(layer "F.CrtYd")
		)
		(fp_rect
			(start -0.55 -0.35)
			(end 0.55 0.35)
			(stroke
				(width 0.15)
				(type solid)
			)
			(fill none)
			(layer "F.Fab")
		)
		(fp_text user "License: Apache-2.0"
			(at -0.8 5.6 90)
			(layer "F.Fab")
			(hide yes)
			(effects
				(font
					(size 0.7 0.7)
					(thickness 0.15)
				)
				(justify left bottom)
			)
		)
		(fp_text user "Author: Antmicro"
			(at -0.8 4.4 90)
			(layer "F.Fab")
			(hide yes)
			(effects
				(font
					(size 0.7 0.7)
					(thickness 0.15)
				)
				(justify left bottom)
			)
		)
		(fp_text user "${REFERENCE}"
			(at -0.8 3.2 90)
			(layer "F.Fab")
			(hide yes)
			(effects
				(font
					(size 0.7 0.7)
					(thickness 0.15)
				)
				(justify left bottom)
			)
		)
		(pad "1" smd roundrect
			(at -0.351 0 90)
			(size 0.3 0.5)
			(layers "F.Cu" "F.Paste" "F.Mask")
			(roundrect_rratio 0.25)
			(net 1 "GND")
			(pinfunction "C")
			(pintype "passive")
		)
		(pad "2" smd roundrect
			(at 0.349 0 90)
			(size 0.3 0.5)
			(layers "F.Cu" "F.Paste" "F.Mask")
			(roundrect_rratio 0.25)
			(net 137 "Net-(D36-A)")
			(pinfunction "A")
			(pintype "passive")
		)
	)
	(footprint "antmicro-footprints:Conn_Molex_Nano-Fit_1x2_SMD_1054301202"
		(layer "F.Cu")
		(at 53.615 124.2105)
		(descr "Molex Nano-Fit Power Connectors, 105430-xx02, 2 Pins per row")
		(tags "connector Molex Nano-Fit")
		(property "Reference" "J12"
			(at -4.985 -4.8705 0)
			(layer "F.SilkS")
			(effects
				(font
					(size 0.7 0.7)
					(thickness 0.15)
				)
				(justify left bottom)
			)
		)
		(property "Value" "Molex_Nano-Fit_1x2_SMD_1054301202"
			(at -0.471 -30.151 0)
			(layer "F.Fab")
			(effects
				(font
					(size 0.7 0.7)
					(thickness 0.15)
				)
				(justify left bottom)
			)
		)
		(property "Footprint" "antmicro-footprints:Conn_Molex_Nano-Fit_1x2_SMD_1054301202"
			(at 0 0 0)
			(layer "F.Fab")
			(hide yes)
			(effects
				(font
					(size 1.27 1.27)
					(thickness 0.15)
				)
			)
		)
		(property "Datasheet" "https://www.farnell.com/cad/3578051.pdf"
			(at 0 0 0)
			(layer "F.Fab")
			(hide yes)
			(effects
				(font
					(size 1.27 1.27)
					(thickness 0.15)
				)
			)
		)
		(property "Author" "Antmicro"
			(at 0 0 0)
			(layer "F.Fab")
			(hide yes)
			(effects
				(font
					(size 1 1)
					(thickness 0.15)
				)
			)
		)
		(property "License" "Apache-2.0"
			(at 0 0 0)
			(layer "F.Fab")
			(hide yes)
			(effects
				(font
					(size 1 1)
					(thickness 0.15)
				)
			)
		)
		(property "MPN" "105430-1202"
			(at 0 0 0)
			(layer "F.Fab")
			(hide yes)
			(effects
				(font
					(size 1 1)
					(thickness 0.15)
				)
			)
		)
		(property "Manufacturer" "Molex"
			(at 0 0 0)
			(layer "F.Fab")
			(hide yes)
			(effects
				(font
					(size 1 1)
					(thickness 0.15)
				)
			)
		)
		(sheetname "Supply")
		(sheetfile "supply.kicad_sch")
		(attr smd)
		(fp_line
			(start -4.47 -4.5)
			(end -4.47 2.099)
			(stroke
				(width 0.15)
				(type solid)
			)
			(layer "F.SilkS")
		)
		(fp_line
			(start -4.47 2.099)
			(end -4.321 2.499)
			(stroke
				(width 0.15)
				(type solid)
			)
			(layer "F.SilkS")
		)
		(fp_line
			(start -4.321 2.499)
			(end -4.321 4.299)
			(stroke
				(width 0.15)
				(type solid)
			)
			(layer "F.SilkS")
		)
		(fp_line
			(start -4.321 4.299)
			(end 4.28 4.299)
			(stroke
				(width 0.15)
				(type solid)
			)
			(layer "F.SilkS")
		)
		(fp_line
			(start -1.72 -4.5)
			(end -4.47 -4.5)
			(stroke
				(width 0.15)
				(type solid)
			)
			(layer "F.SilkS")
		)
		(fp_line
			(start -0.22 -4.5)
			(end 0.78 -4.5)
			(stroke
				(width 0.15)
				(type solid)
			)
			(layer "F.SilkS")
		)
		(fp_line
			(start 4.28 2.698)
			(end 4.28 4.299)
			(stroke
				(width 0.15)
				(type solid)
			)
			(layer "F.SilkS")
		)
		(fp_line
			(start 4.48 -4.5)
			(end 2.68 -4.5)
			(stroke
				(width 0.15)
				(type solid)
			)
			(layer "F.SilkS")
		)
		(fp_line
			(start 4.48 2.298)
			(end 4.28 2.698)
			(stroke
				(width 0.15)
				(type solid)
			)
			(layer "F.SilkS")
		)
		(fp_line
			(start 4.48 2.298)
			(end 4.48 -4.5)
			(stroke
				(width 0.15)
				(type solid)
			)
			(layer "F.SilkS")
		)
		(fp_circle
			(center 2.428 -4.91)
			(end 2.478 -4.91)
			(stroke
				(width 0.15)
				(type solid)
			)
			(fill solid)
			(layer "F.SilkS")
		)
		(fp_rect
			(start -4.77 -6.21)
			(end 4.77 6.11)
			(stroke
				(width 0.05)
				(type solid)
			)
			(fill none)
			(layer "F.CrtYd")
		)
		(fp_text user "${REFERENCE}"
			(at 0 7.2 0)
			(layer "F.Fab")
			(hide yes)
			(effects
				(font
					(size 0.7 0.7)
					(thickness 0.15)
				)
				(justify left bottom)
			)
		)
		(fp_text user "Author: Antmicro"
			(at 0 9 0)
			(layer "F.Fab")
			(hide yes)
			(effects
				(font
					(size 0.7 0.7)
					(thickness 0.15)
				)
				(justify left bottom)
			)
		)
		(fp_text user "License: Apache-2.0"
			(at 0 10.199 0)
			(layer "F.Fab")
			(hide yes)
			(effects
				(font
					(size 0.7 0.7)
					(thickness 0.15)
				)
				(justify left bottom)
			)
		)
		(pad "1" smd roundrect
			(at 1.528 -4.901 90)
			(size 2.5 1.24)
			(layers "F.Cu" "F.Paste" "F.Mask")
			(roundrect_rratio 0.25)
			(net 189 "Net-(D28-C)")
			(pintype "passive")
		)
		(pad "2" smd roundrect
			(at -0.97 -4.901 90)
			(size 2.5 1.24)
			(layers "F.Cu" "F.Paste" "F.Mask")
			(roundrect_rratio 0.25)
			(net 1 "GND")
			(pintype "passive")
		)
		(pad "MP" smd roundrect
			(at -3.54 0.029)
			(size 1.1 8.2)
			(layers "F.Cu" "F.Paste" "F.Mask")
			(roundrect_rratio 0.25)
			(net 1 "GND")
			(pintype "passive")
		)
		(pad "MP" smd roundrect
			(at 3.499 0.029)
			(size 1.1 8.2)
			(layers "F.Cu" "F.Paste" "F.Mask")
			(roundrect_rratio 0.25)
			(net 1 "GND")
			(pintype "passive")
		)
	)
	(footprint "antmicro-footprints:R_Array_4x0201_Panasonic_EXB18V"
		(layer "F.Cu")
		(at 114.55 94.25 -90)
		(property "Reference" "R22"
			(at 1.02 0.84 90)
			(layer "F.SilkS")
			(effects
				(font
					(size 0.7 0.7)
					(thickness 0.15)
				)
				(justify left bottom)
			)
		)
		(property "Value" "R_4x0R_0201_array"
			(at -1.1 1.8 -90)
			(layer "F.Fab")
			(effects
				(font
					(size 0.7 0.7)
					(thickness 0.15)
				)
				(justify left bottom)
			)
		)
		(property "Footprint" "antmicro-footprints:R_Array_4x0201_Panasonic_EXB18V"
			(at 0 0 -90)
			(layer "F.Fab")
			(hide yes)
			(effects
				(font
					(size 1.27 1.27)
					(thickness 0.15)
				)
			)
		)
		(property "Datasheet" "http://industrial.panasonic.com/cdbs/www-data/pdf/AOC0000/AOC0000C14.pdf"
			(at 0 0 -90)
			(layer "F.Fab")
			(hide yes)
			(effects
				(font
					(size 1.27 1.27)
					(thickness 0.15)
				)
			)
		)
		(property "Author" "Antmicro"
			(at 20.3 208.8 0)
			(layer "F.Fab")
			(hide yes)
			(effects
				(font
					(size 1 1)
					(thickness 0.15)
				)
			)
		)
		(property "License" "Apache-2.0"
			(at 20.3 208.8 0)
			(layer "F.Fab")
			(hide yes)
			(effects
				(font
					(size 1 1)
					(thickness 0.15)
				)
			)
		)
		(property "MPN" "EXB-18VR000X"
			(at 20.3 208.8 0)
			(layer "F.Fab")
			(hide yes)
			(effects
				(font
					(size 1 1)
					(thickness 0.15)
				)
			)
		)
		(property "Manufacturer" "Panasonic"
			(at 20.3 208.8 0)
			(layer "F.Fab")
			(hide yes)
			(effects
				(font
					(size 1 1)
					(thickness 0.15)
				)
			)
		)
		(property "Val" "4x0R_0201"
			(at 20.3 208.8 0)
			(layer "F.Fab")
			(hide yes)
			(effects
				(font
					(size 1 1)
					(thickness 0.15)
				)
			)
		)
		(sheetname "M.2")
		(sheetfile "m-2.kicad_sch")
		(attr smd)
		(fp_line
			(start -0.8 -0.45)
			(end -0.8 0.45)
			(stroke
				(width 0.12)
				(type solid)
			)
			(layer "F.SilkS")
		)
		(fp_line
			(start 0.8 -0.45)
			(end 0.8 0.45)
			(stroke
				(width 0.12)
				(type solid)
			)
			(layer "F.SilkS")
		)
		(fp_rect
			(start -0.898 -0.66)
			(end 0.898 0.65)
			(stroke
				(width 0.05)
				(type solid)
			)
			(fill none)
			(layer "F.CrtYd")
		)
		(fp_text user "${REFERENCE}"
			(at -1.051 3.2 -90)
			(layer "F.Fab")
			(hide yes)
			(effects
				(font
					(size 0.7 0.7)
					(thickness 0.15)
				)
				(justify left bottom)
			)
		)
		(fp_text user "Author: Antmicro"
			(at -1.051 4.599 -90)
			(layer "F.Fab")
			(hide yes)
			(effects
				(font
					(size 0.7 0.7)
					(thickness 0.15)
				)
				(justify left bottom)
			)
		)
		(fp_text user "License: Apache-2.0"
			(at -1.051 6 -90)
			(layer "F.Fab")
			(hide yes)
			(effects
				(font
					(size 0.7 0.7)
					(thickness 0.15)
				)
				(justify left bottom)
			)
		)
		(pad "1" smd roundrect
			(at -0.6 0.298 270)
			(size 0.2 0.4)
			(layers "F.Cu" "F.Paste" "F.Mask")
			(roundrect_rratio 0.25)
			(net 517 "UART0_TXD")
			(pinfunction "R1.1")
			(pintype "passive")
		)
		(pad "2" smd roundrect
			(at -0.202 0.298 270)
			(size 0.2 0.4)
			(layers "F.Cu" "F.Paste" "F.Mask")
			(roundrect_rratio 0.25)
			(net 119 "UART0_CTS")
			(pinfunction "R2.1")
			(pintype "passive")
		)
		(pad "3" smd roundrect
			(at 0.2 0.298 270)
			(size 0.2 0.4)
			(layers "F.Cu" "F.Paste" "F.Mask")
			(roundrect_rratio 0.25)
			(net 118 "UART0_RTS")
			(pinfunction "R3.1")
			(pintype "passive")
		)
		(pad "4" smd roundrect
			(at 0.598 0.298 270)
			(size 0.2 0.4)
			(layers "F.Cu" "F.Paste" "F.Mask")
			(roundrect_rratio 0.25)
			(net 516 "UART0_RXD")
			(pinfunction "R4.1")
			(pintype "passive")
		)
		(pad "5" smd roundrect
			(at 0.598 -0.3 270)
			(size 0.2 0.4)
			(layers "F.Cu" "F.Paste" "F.Mask")
			(roundrect_rratio 0.25)
			(net 192 "/M.2/M2_E_UART_RX")
			(pinfunction "R4.2")
			(pintype "passive")
		)
		(pad "6" smd roundrect
			(at 0.2 -0.3 270)
			(size 0.2 0.4)
			(layers "F.Cu" "F.Paste" "F.Mask")
			(roundrect_rratio 0.25)
			(net 195 "/M.2/M2_E_UART_RTS")
			(pinfunction "R3.2")
			(pintype "passive")
		)
		(pad "7" smd roundrect
			(at -0.202 -0.3 270)
			(size 0.2 0.4)
			(layers "F.Cu" "F.Paste" "F.Mask")
			(roundrect_rratio 0.25)
			(net 199 "/M.2/M2_E_UART_CTS")
			(pinfunction "R2.2")
			(pintype "passive")
		)
		(pad "8" smd roundrect
			(at -0.6 -0.3 270)
			(size 0.2 0.4)
			(layers "F.Cu" "F.Paste" "F.Mask")
			(roundrect_rratio 0.25)
			(net 188 "/M.2/M2_E_UART_TX")
			(pinfunction "R1.2")
			(pintype "passive")
		)
	)
)
